# BASEBOARD_FAB2 (Tioga Pass) — schematic netlist excerpt (pin names and nets, part order shuffled) for the footprints in the layout excerpt that follows; sources: Cadence DE-HDL packaged netlist, KiCad conversion of Wiwynn_Tioga_Pass_MB.brd

EU7E1  SLG55021  IC  pkg SM  page 198
  VCC  = P5V_STBY
  \on\  = FM_P12V_MAIN_SW_EN
  SHDN_N  = P5V_STBY
  GND  = GND
  D  = P12V_STBY
  S  = P12V
  G  = P12V_SWITCH_G
  PG  = TP_SLG55021_P12V_MAIN_8
  THPAD  = GND

C4G16  CAP  1.0UF 16V 10% X6S  pkg 0402  page 221 : A = VR_PVTT_ABC_VREF ; B = GND
C3M7  CAP_A  22.0UF 4V 20% X6S  pkg 0603V  page 132 : A = PVNN_PCH_STBY ; B = GND

(kicad_pcb
	(version 20260206)
	(generator "pcbnew")
	(generator_version "10.0")
	(general
		(thickness 1.6)
		(legacy_teardrops no)
	)
	(paper "A4")
	(title_block
		(title "Wiwynn_Tioga_Pass_MB.brd")
		(comment 1 "Tioga Pass / footprints 784-786 of 4770")
	)
	(layers
		(0 "F.Cu" signal "TOP")
		(4 "In1.Cu" signal "L2GND")
		(6 "In2.Cu" signal "L3")
		(8 "In3.Cu" signal "L4GND")
		(10 "In4.Cu" signal "L5")
		(12 "In5.Cu" signal "L6GND")
		(14 "In6.Cu" signal "L7VCC")
		(16 "In7.Cu" signal "L8VCC")
		(18 "In8.Cu" signal "L9GND")
		(20 "In9.Cu" signal "L10")
		(22 "In10.Cu" signal "L11GND")
		(24 "In11.Cu" signal "L12")
		(26 "In12.Cu" signal "L13GND")
		(2 "B.Cu" signal "BOTTOM")
		(9 "F.Adhes" user "F.Adhesive")
		(11 "B.Adhes" user "B.Adhesive")
		(13 "F.Paste" user "Package Geometry/Pastemask Top")
		(15 "B.Paste" user "Package Geometry/Pastemask Bottom")
		(5 "F.SilkS" user "Ref Des/Silkscreen Top")
		(7 "B.SilkS" user "Ref Des/Silkscreen Bottom")
		(1 "F.Mask" user "Board Geometry/Soldermask Top")
		(3 "B.Mask" user "Board Geometry/Soldermask Bottom")
		(17 "Dwgs.User" user "User.Drawings")
		(19 "Cmts.User" user "User.Comments")
		(21 "Eco1.User" user "User.Eco1")
		(23 "Eco2.User" user "User.Eco2")
		(25 "Edge.Cuts" user "Board Geometry/Outline")
		(27 "Margin" user)
		(31 "F.CrtYd" user "Package Geometry/Place Bound Top")
		(29 "B.CrtYd" user "Package Geometry/Place Bound Bottom")
		(35 "F.Fab" user "Ref Des/Assembly Top")
		(33 "B.Fab" user "Ref Des/Assembly Bottom")
	)
	(footprint ""
		(layer "F.Cu")
		(at 496.678204 -26.555192)
		(property "Reference" "EU7E1"
			(at 1.8415 2.376932 180)
			(unlocked yes)
			(layer "F.SilkS")
			(effects
				(font
					(size 0.7874 0.5842)
					(thickness 0.1524)
				)
				(justify left)
			)
		)
		(property "Value" ""
			(at 0 0 0)
			(layer "F.Fab")
			(effects
				(font
					(size 1.27 1.27)
				)
			)
		)
		(duplicate_pad_numbers_are_jumpers no)
		(fp_circle
			(center -0.702056 -0.595376)
			(end -0.575056 -0.595376)
			(stroke
				(width 0.254)
				(type default)
			)
			(fill no)
			(layer "F.SilkS")
		)
		(fp_rect
			(start 0.5842 1.549908)
			(end 1.4732 -0.050292)
			(stroke
				(width 0)
				(type default)
			)
			(fill yes)
			(layer "F.Paste")
		)
		(fp_rect
			(start -0.021336 1.799844)
			(end 2.078736 -0.300228)
			(stroke
				(width 0)
				(type default)
			)
			(fill no)
			(layer "F.CrtYd")
		)
		(fp_line
			(start -0.021336 -0.300228)
			(end 2.078736 -0.300228)
			(stroke
				(width 0.1)
				(type default)
			)
			(layer "F.Fab")
		)
		(fp_line
			(start -0.021336 1.799844)
			(end -0.021336 -0.300228)
			(stroke
				(width 0.1)
				(type default)
			)
			(layer "F.Fab")
		)
		(fp_line
			(start 2.078736 -0.300228)
			(end 2.078736 1.799844)
			(stroke
				(width 0.1)
				(type default)
			)
			(layer "F.Fab")
		)
		(fp_line
			(start 2.078736 1.799844)
			(end -0.021336 1.799844)
			(stroke
				(width 0.1)
				(type default)
			)
			(layer "F.Fab")
		)
		(fp_circle
			(center -0.702056 -0.595376)
			(end -0.575056 -0.595376)
			(stroke
				(width 0.254)
				(type default)
			)
			(fill no)
			(layer "F.Fab")
		)
		(pad "1" smd rect
			(at 0 0)
			(size 0.6604 0.3048)
			(layers "F.Cu" "F.Mask" "F.Paste")
			(net "P5V_STBY")
		)
		(pad "2" smd rect
			(at 0 0.499872)
			(size 0.6604 0.3048)
			(layers "F.Cu" "F.Mask" "F.Paste")
			(net "FM_P12V_MAIN_SW_EN")
		)
		(pad "3" smd rect
			(at 0 0.999744)
			(size 0.6604 0.3048)
			(layers "F.Cu" "F.Mask" "F.Paste")
			(net "P5V_STBY")
		)
		(pad "4" smd rect
			(at 0 1.499616)
			(size 0.6604 0.3048)
			(layers "F.Cu" "F.Mask" "F.Paste")
			(net "GND")
		)
		(pad "5" smd rect
			(at 2.0574 1.499616)
			(size 0.6604 0.3048)
			(layers "F.Cu" "F.Mask" "F.Paste")
			(net "P12V_STBY")
		)
		(pad "6" smd rect
			(at 2.0574 0.999744)
			(size 0.6604 0.3048)
			(layers "F.Cu" "F.Mask" "F.Paste")
			(net "P12V")
		)
		(pad "7" smd rect
			(at 2.0574 0.499872)
			(size 0.6604 0.3048)
			(layers "F.Cu" "F.Mask" "F.Paste")
			(net "P12V_SWITCH_G")
		)
		(pad "8" smd rect
			(at 2.0574 0)
			(size 0.6604 0.3048)
			(layers "F.Cu" "F.Mask" "F.Paste")
			(net "TP_SLG55021_P12V_MAIN_8")
		)
		(pad "9" smd rect
			(at 1.0287 0.749808)
			(size 0.889 1.6002)
			(layers "F.Cu" "F.Mask" "F.Paste")
			(net "GND")
		)
	)
	(footprint ""
		(layer "F.Cu")
		(at 184.531 -4.2545 180)
		(property "Reference" "C4G16"
			(at 0 0 180)
			(layer "F.SilkS")
			(hide yes)
			(effects
				(font
					(size 1.27 1.27)
				)
			)
		)
		(property "Value" ""
			(at 0 0 180)
			(layer "F.Fab")
			(effects
				(font
					(size 1.27 1.27)
				)
			)
		)
		(duplicate_pad_numbers_are_jumpers no)
		(fp_rect
			(start 0.3048 -0.1016)
			(end -0.3048 0.9906)
			(stroke
				(width 0)
				(type default)
			)
			(fill no)
			(layer "F.CrtYd")
		)
		(fp_line
			(start 0.3048 0.9906)
			(end 0.3048 -0.1016)
			(stroke
				(width 0.1)
				(type default)
			)
			(layer "F.Fab")
		)
		(fp_line
			(start 0.3048 -0.1016)
			(end -0.3048 -0.1016)
			(stroke
				(width 0.1)
				(type default)
			)
			(layer "F.Fab")
		)
		(fp_line
			(start -0.3048 0.9906)
			(end 0.3048 0.9906)
			(stroke
				(width 0.1)
				(type default)
			)
			(layer "F.Fab")
		)
		(fp_line
			(start -0.3048 -0.1016)
			(end -0.3048 0.9906)
			(stroke
				(width 0.1)
				(type default)
			)
			(layer "F.Fab")
		)
		(pad "1" smd rect
			(at 0 0 180)
			(size 0.508 0.508)
			(layers "F.Cu" "F.Mask" "F.Paste")
			(net "VR_PVTT_ABC_VREF")
		)
		(pad "2" smd rect
			(at 0 0.889 180)
			(size 0.508 0.508)
			(layers "F.Cu" "F.Mask" "F.Paste")
			(net "GND")
		)
		(zone
			(layer "F.Cu")
			(hatch none 0.5)
			(connect_pads
				(clearance 0)
			)
			(min_thickness 0.25)
			(keepout
				(tracks not_allowed)
				(vias allowed)
				(pads allowed)
				(copperpour not_allowed)
				(footprints allowed)
			)
			(placement
				(enabled no)
				(sheetname "")
			)
			(fill
				(thermal_gap 0.5)
				(thermal_bridge_width 0.5)
				(island_removal_mode 0)
			)
			(polygon
				(pts
					(xy 184.277 -4.5085) (xy 184.785 -4.5085) (xy 184.785 -4.8895) (xy 184.277 -4.8895)
				)
			)
		)
		(zone
			(layer "F.Cu")
			(hatch none 0.5)
			(connect_pads
				(clearance 0)
			)
			(min_thickness 0.25)
			(keepout
				(tracks allowed)
				(vias not_allowed)
				(pads allowed)
				(copperpour not_allowed)
				(footprints allowed)
			)
			(placement
				(enabled no)
				(sheetname "")
			)
			(fill
				(thermal_gap 0.5)
				(thermal_bridge_width 0.5)
				(island_removal_mode 0)
			)
			(polygon
				(pts
					(xy 184.277 -4.5085) (xy 184.785 -4.5085) (xy 184.785 -4.8895) (xy 184.277 -4.8895)
				)
			)
		)
	)
	(footprint ""
		(layer "F.Cu")
		(at 381.4572 -140.4366 90)
		(property "Reference" "C3M7"
			(at 0 0 90)
			(layer "F.SilkS")
			(hide yes)
			(effects
				(font
					(size 1.27 1.27)
				)
			)
		)
		(property "Value" ""
			(at 0 0 90)
			(layer "F.Fab")
			(effects
				(font
					(size 1.27 1.27)
				)
			)
		)
		(duplicate_pad_numbers_are_jumpers no)
		(fp_rect
			(start -0.4953 -0.2032)
			(end 0.4953 1.6002)
			(stroke
				(width 0)
				(type default)
			)
			(fill no)
			(layer "F.CrtYd")
		)
		(fp_line
			(start 0.4953 -0.2032)
			(end 0.4953 1.6002)
			(stroke
				(width 0.1)
				(type default)
			)
			(layer "F.Fab")
		)
		(fp_line
			(start -0.4953 -0.2032)
			(end 0.4953 -0.2032)
			(stroke
				(width 0.1)
				(type default)
			)
			(layer "F.Fab")
		)
		(fp_line
			(start 0.4953 1.6002)
			(end -0.4953 1.6002)
			(stroke
				(width 0.1)
				(type default)
			)
			(layer "F.Fab")
		)
		(fp_line
			(start -0.4953 1.6002)
			(end -0.4953 -0.2032)
			(stroke
				(width 0.1)
				(type default)
			)
			(layer "F.Fab")
		)
		(pad "1" smd rect
			(at 0 0 90)
			(size 0.762 0.889)
			(layers "F.Cu" "F.Mask" "F.Paste")
			(net "PVNN_PCH_STBY")
		)
		(pad "2" smd rect
			(at 0 1.397 90)
			(size 0.762 0.889)
			(layers "F.Cu" "F.Mask" "F.Paste")
			(net "GND")
		)
		(zone
			(layer "F.Cu")
			(hatch none 0.5)
			(connect_pads
				(clearance 0)
			)
			(min_thickness 0.25)
			(keepout
				(tracks not_allowed)
				(vias allowed)
				(pads allowed)
				(copperpour not_allowed)
				(footprints allowed)
			)
			(placement
				(enabled no)
				(sheetname "")
			)
			(fill
				(thermal_gap 0.5)
				(thermal_bridge_width 0.5)
				(island_removal_mode 0)
			)
			(polygon
				(pts
					(xy 381.9017 -140.0556) (xy 382.4097 -140.0556) (xy 382.4097 -140.8176) (xy 381.9017 -140.8176)
				)
			)
		)
	)
)
